#ISCELL
  mstr_misc dns *
  *
#ISCELL
  pure_quanta quanta_title_block_c *
  *
#ISCELL
  pure_quanta_power cad_note *
  *
#CELL
  pure_quanta sn74avc2t245rswr *
  page149_i1
#CELL
  pure_quanta q_cap *
  page149_i10
#CELL
  pure_quanta q_res *
  page149_i101
#CELL
  pure_quanta mosfet_n *
  page149_i102
#CELL
  pure_quanta q_res *
  page149_i109
#ISCELL
  pure_quanta_power gnd *
  page149_i11
#ISCELL
  pure_quanta_power gnd *
  page149_i110
#CELL
  pure_quanta q_res *
  page149_i111
#CELL
  pure_quanta q_res *
  page149_i112
#CELL
  pure_quanta q_res *
  page149_i113
#CELL
  pure_quanta q_res *
  page149_i114
#CELL
  pure_quanta q_res *
  page149_i115
#CELL
  pure_quanta q_res *
  page149_i116
#CELL
  pure_quanta q_res *
  page149_i117
#CELL
  pure_quanta q_res *
  page149_i118
#ISCELL
  pure_quanta_power universal_power *
  page149_i119
#ISCELL
  pure_quanta_power universal_power *
  page149_i12
#ISCELL
  pure_quanta_power gnd *
  page149_i120
#ISCELL
  pure_quanta_power gnd *
  page149_i121
#CELL
  pure_quanta q_cap *
  page149_i123
#ISCELL
  standard offpage *
  page149_i124
#ISCELL
  standard offpage *
  page149_i125
#ISCELL
  standard offpage *
  page149_i126
#ISCELL
  standard offpage *
  page149_i127
#ISCELL
  standard offpage *
  page149_i128
#ISCELL
  standard offpage *
  page149_i129
#ISCELL
  standard offpage *
  page149_i130
#ISCELL
  standard offpage *
  page149_i131
#CELL
  pure_quanta q_res *
  page149_i132
#CELL
  pure_quanta q_res *
  page149_i133
#CELL
  pure_quanta q_cap *
  page149_i134
#CELL
  pure_quanta q_cap *
  page149_i137
#ISCELL
  pure_quanta_power gnd *
  page149_i138
#CELL
  pure_quanta q_cap *
  page149_i140
#ISCELL
  pure_quanta_power gnd *
  page149_i141
#CELL
  pure_quanta sconn20_hsu2101l00007h *
  page149_i142
#ISCELL
  pure_quanta_power gnd *
  page149_i143
#ISCELL
  pure_quanta_power universal_power *
  page149_i144
#ISCELL
  pure_quanta_power universal_power *
  page149_i145
#CELL
  pure_quanta q_res *
  page149_i146
#CELL
  pure_quanta q_res *
  page149_i147
#CELL
  pure_quanta q_res *
  page149_i148
#CELL
  pure_quanta q_res *
  page149_i149
#CELL
  pure_quanta q_res *
  page149_i150
#ISCELL
  pure_quanta_power gnd *
  page149_i151
#CELL
  pure_quanta q_cap *
  page149_i152
#ISCELL
  standard offpage *
  page149_i153
#ISCELL
  standard offpage *
  page149_i154
#ISCELL
  standard offpage *
  page149_i155
#ISCELL
  standard offpage *
  page149_i156
#CELL
  pure_quanta q_res *
  page149_i157
#ISCELL
  standard offpage *
  page149_i158
#CELL
  pure_quanta q_res *
  page149_i159
#CELL
  pure_quanta q_res *
  page149_i160
#CELL
  pure_quanta q_cap *
  page149_i161
#ISCELL
  pure_quanta_power gnd *
  page149_i162
#CELL
  pure_quanta q_cap *
  page149_i163
#ISCELL
  pure_quanta_power gnd *
  page149_i164
#ISCELL
  pure_quanta_power universal_power *
  page149_i20
#CELL
  pure_quanta q_cap *
  page149_i21
#ISCELL
  pure_quanta_power gnd *
  page149_i22
#CELL
  pure_quanta q_cap *
  page149_i23
#ISCELL
  pure_quanta_power gnd *
  page149_i24
#CELL
  pure_quanta q_cap *
  page149_i25
#ISCELL
  pure_quanta_power gnd *
  page149_i26
#ISCELL
  pure_quanta_power gnd *
  page149_i27
#ISCELL
  pure_quanta_power universal_power *
  page149_i28
#CELL
  pure_quanta q_cap *
  page149_i29
#ISCELL
  standard offpage *
  page149_i3
#ISCELL
  pure_quanta_power gnd *
  page149_i30
#CELL
  pure_quanta sn74avc4t774pwr *
  page149_i31
#ISCELL
  pure_quanta_power universal_power *
  page149_i32
#ISCELL
  pure_quanta_power gnd *
  page149_i33
#CELL
  pure_quanta sn74avc4t774pwr *
  page149_i34
#ISCELL
  standard offpage *
  page149_i4
#CELL
  pure_quanta q_cap *
  page149_i41
#ISCELL
  pure_quanta_power gnd *
  page149_i42
#ISCELL
  standard offpage *
  page149_i43
#ISCELL
  standard offpage *
  page149_i44
#ISCELL
  standard offpage *
  page149_i45
#ISCELL
  standard offpage *
  page149_i46
#ISCELL
  standard offpage *
  page149_i5
#ISCELL
  standard offpage *
  page149_i51
#CELL
  pure_quanta q_res *
  page149_i53
#ISCELL
  pure_quanta_power universal_power *
  page149_i54
#ISCELL
  pure_quanta_power gnd *
  page149_i55
#CELL
  pure_quanta q_cap *
  page149_i56
#ISCELL
  standard offpage *
  page149_i6
#CELL
  pure_quanta q_cap *
  page149_i62
#ISCELL
  pure_quanta_power gnd *
  page149_i63
#ISCELL
  standard offpage *
  page149_i64
#ISCELL
  standard offpage *
  page149_i65
#ISCELL
  standard offpage *
  page149_i68
#ISCELL
  standard offpage *
  page149_i69
#CELL
  pure_quanta q_res *
  page149_i7
#ISCELL
  standard offpage *
  page149_i70
#ISCELL
  pure_quanta_power universal_power *
  page149_i71
#ISCELL
  pure_quanta_power universal_power *
  page149_i73
#CELL
  pure_quanta q_cap *
  page149_i74
#ISCELL
  pure_quanta_power gnd *
  page149_i75
#CELL
  pure_quanta sn74avc2t245rswr *
  page149_i76
#ISCELL
  pure_quanta_power gnd *
  page149_i77
#ISCELL
  pure_quanta_power universal_power *
  page149_i78
#CELL
  pure_quanta q_res *
  page149_i8
#CELL
  pure_quanta q_cap *
  page149_i80
#ISCELL
  pure_quanta_power gnd *
  page149_i81
#ISCELL
  pure_quanta_power universal_power *
  page149_i82
#CELL
  pure_quanta q_res *
  page149_i83
#ISCELL
  pure_quanta_power gnd *
  page149_i84
#ISCELL
  pure_quanta_power gnd *
  page149_i85
#CELL
  pure_quanta q_res *
  page149_i9
#ISCELL
  standard offpage *
  page149_i90
#ISCELL
  standard offpage *
  page149_i91
#CELL
  pure_quanta q_res *
  page149_i92
#ISCELL
  standard offpage *
  page149_i93
#ISCELL
  standard offpage *
  page149_i94
#ISCELL
  standard offpage *
  page149_i95
#CELL
  pure_quanta q_res *
  page149_i96
